# S9S_MB_2U (Grand Teton) — schematic netlist excerpt (pin names and nets, part order shuffled) for the footprints in the layout excerpt that follows; sources: Cadence DE-HDL packaged netlist, KiCad conversion of 03242023_DA0F0TMBIJ0_F0T_Motherboard_J_brd_V01_OCP.brd

PC1173  Q_CAP  1UF 16V 10% X6S  pkg C0402  page 266 : A = PVCCIN_CPU0_VREF ; B = GND
PR2538  Q_RES  10 1% EMPTY  pkg 0402LF  page 304 : A = MB0_CM_GATE_G0 ; B = P12V_HSC_GATE1

(kicad_pcb
	(version 20260206)
	(generator "pcbnew")
	(generator_version "10.0")
	(general
		(thickness 1.6)
		(legacy_teardrops no)
	)
	(paper "A4")
	(title_block
		(title "03242023_DA0F0TMBIJ0_F0T_Motherboard_J_brd_V01_OCP.brd")
		(comment 1 "Grand Teton / footprints 1877-1878 of 6105")
	)
	(layers
		(0 "F.Cu" signal "TOP")
		(4 "In1.Cu" signal "GND")
		(6 "In2.Cu" signal "IN1")
		(8 "In3.Cu" signal "GND1")
		(10 "In4.Cu" signal "IN2")
		(12 "In5.Cu" signal "GND2")
		(14 "In6.Cu" signal "IN3")
		(16 "In7.Cu" signal "GND3")
		(18 "In8.Cu" signal "VCC")
		(20 "In9.Cu" signal "VCC1")
		(22 "In10.Cu" signal "GND4")
		(24 "In11.Cu" signal "IN4")
		(26 "In12.Cu" signal "GND5")
		(28 "In13.Cu" signal "IN5")
		(30 "In14.Cu" signal "GND6")
		(32 "In15.Cu" signal "IN6")
		(34 "In16.Cu" signal "GND7")
		(2 "B.Cu" signal "BOTTOM")
		(9 "F.Adhes" user "F.Adhesive")
		(11 "B.Adhes" user "B.Adhesive")
		(13 "F.Paste" user "Package Geometry/Pastemask Top")
		(15 "B.Paste" user "Package Geometry/Pastemask Bottom")
		(5 "F.SilkS" user "Ref Des/Silkscreen Top")
		(7 "B.SilkS" user "Ref Des/Silkscreen Bottom")
		(1 "F.Mask" user "Board Geometry/Soldermask Top")
		(3 "B.Mask" user "Board Geometry/Soldermask Bottom")
		(17 "Dwgs.User" user "User.Drawings")
		(19 "Cmts.User" user "User.Comments")
		(21 "Eco1.User" user "User.Eco1")
		(23 "Eco2.User" user "User.Eco2")
		(25 "Edge.Cuts" user "Board Geometry/Outline")
		(27 "Margin" user)
		(31 "F.CrtYd" user "Package Geometry/Place Bound Top")
		(29 "B.CrtYd" user "Package Geometry/Place Bound Bottom")
		(35 "F.Fab" user "Ref Des/Assembly Top")
		(33 "B.Fab" user "Ref Des/Assembly Bottom")
	)
	(footprint ""
		(layer "F.Cu")
		(at 280.20645 -394.17117)
		(property "Reference" "PR2538"
			(at 0 0 0)
			(layer "F.SilkS")
			(hide yes)
			(effects
				(font
					(size 1.27 1.27)
				)
			)
		)
		(property "Value" ""
			(at 0 0 0)
			(layer "F.Fab")
			(effects
				(font
					(size 1.27 1.27)
				)
			)
		)
		(duplicate_pad_numbers_are_jumpers no)
		(fp_line
			(start -0.7874 -0.4064)
			(end 0.7874 -0.4064)
			(stroke
				(width 0.1524)
				(type default)
			)
			(layer "F.SilkS")
		)
		(fp_line
			(start -0.7874 0.4064)
			(end -0.7874 -0.4064)
			(stroke
				(width 0.1524)
				(type default)
			)
			(layer "F.SilkS")
		)
		(fp_line
			(start 0.7874 -0.4064)
			(end 0.7874 0.4064)
			(stroke
				(width 0.1524)
				(type default)
			)
			(layer "F.SilkS")
		)
		(fp_line
			(start 0.7874 0.4064)
			(end -0.7874 0.4064)
			(stroke
				(width 0.1524)
				(type default)
			)
			(layer "F.SilkS")
		)
		(fp_line
			(start -0.67945 -0.305054)
			(end -0.12065 -0.305054)
			(stroke
				(width 0.1)
				(type default)
			)
			(layer "F.Fab")
		)
		(fp_line
			(start -0.67945 0.3048)
			(end -0.67945 -0.305054)
			(stroke
				(width 0.1)
				(type default)
			)
			(layer "F.Fab")
		)
		(fp_line
			(start -0.12065 -0.305054)
			(end -0.12065 -0.2794)
			(stroke
				(width 0.1)
				(type default)
			)
			(layer "F.Fab")
		)
		(fp_line
			(start -0.12065 -0.2794)
			(end 0.12065 -0.2794)
			(stroke
				(width 0.1)
				(type default)
			)
			(layer "F.Fab")
		)
		(fp_line
			(start -0.12065 0.2794)
			(end -0.12065 0.3048)
			(stroke
				(width 0.1)
				(type default)
			)
			(layer "F.Fab")
		)
		(fp_line
			(start -0.12065 0.3048)
			(end -0.67945 0.3048)
			(stroke
				(width 0.1)
				(type default)
			)
			(layer "F.Fab")
		)
		(fp_line
			(start 0.120396 0.2794)
			(end -0.12065 0.2794)
			(stroke
				(width 0.1)
				(type default)
			)
			(layer "F.Fab")
		)
		(fp_line
			(start 0.120396 0.3048)
			(end 0.120396 0.2794)
			(stroke
				(width 0.1)
				(type default)
			)
			(layer "F.Fab")
		)
		(fp_line
			(start 0.12065 -0.3048)
			(end 0.67945 -0.3048)
			(stroke
				(width 0.1)
				(type default)
			)
			(layer "F.Fab")
		)
		(fp_line
			(start 0.12065 -0.2794)
			(end 0.12065 -0.3048)
			(stroke
				(width 0.1)
				(type default)
			)
			(layer "F.Fab")
		)
		(fp_line
			(start 0.67945 -0.3048)
			(end 0.67945 0.3048)
			(stroke
				(width 0.1)
				(type default)
			)
			(layer "F.Fab")
		)
		(fp_line
			(start 0.67945 0.3048)
			(end 0.120396 0.3048)
			(stroke
				(width 0.1)
				(type default)
			)
			(layer "F.Fab")
		)
		(pad "1" smd circle
			(at -0.40005 0)
			(size 0 0)
			(layers "F.Cu" "F.Mask" "F.Paste")
			(net "MB0_CM_GATE_G0")
		)
		(pad "2" smd circle
			(at 0.40005 0)
			(size 0 0)
			(layers "F.Cu" "F.Mask" "F.Paste")
			(net "P12V_HSC_GATE1")
		)
	)
	(footprint ""
		(layer "F.Cu")
		(at 361.573826 -365.290354 90)
		(property "Reference" "PC1173"
			(at 0 0 90)
			(layer "F.SilkS")
			(hide yes)
			(effects
				(font
					(size 1.27 1.27)
				)
			)
		)
		(property "Value" ""
			(at 0 0 90)
			(layer "F.Fab")
			(effects
				(font
					(size 1.27 1.27)
				)
			)
		)
		(duplicate_pad_numbers_are_jumpers no)
		(fp_line
			(start 0.7874 -0.4064)
			(end 0.7874 0.4064)
			(stroke
				(width 0.1524)
				(type default)
			)
			(layer "F.SilkS")
		)
		(fp_line
			(start -0.7874 -0.4064)
			(end 0.7874 -0.4064)
			(stroke
				(width 0.1524)
				(type default)
			)
			(layer "F.SilkS")
		)
		(fp_line
			(start 0.7874 0.4064)
			(end -0.7874 0.4064)
			(stroke
				(width 0.1524)
				(type default)
			)
			(layer "F.SilkS")
		)
		(fp_line
			(start -0.7874 0.4064)
			(end -0.7874 -0.4064)
			(stroke
				(width 0.1524)
				(type default)
			)
			(layer "F.SilkS")
		)
		(fp_line
			(start -0.12065 -0.305054)
			(end -0.12065 -0.2794)
			(stroke
				(width 0.1)
				(type default)
			)
			(layer "F.Fab")
		)
		(fp_line
			(start -0.67945 -0.305054)
			(end -0.12065 -0.305054)
			(stroke
				(width 0.1)
				(type default)
			)
			(layer "F.Fab")
		)
		(fp_line
			(start 0.67945 -0.3048)
			(end 0.67945 0.3048)
			(stroke
				(width 0.1)
				(type default)
			)
			(layer "F.Fab")
		)
		(fp_line
			(start 0.12065 -0.3048)
			(end 0.67945 -0.3048)
			(stroke
				(width 0.1)
				(type default)
			)
			(layer "F.Fab")
		)
		(fp_line
			(start 0.12065 -0.2794)
			(end 0.12065 -0.3048)
			(stroke
				(width 0.1)
				(type default)
			)
			(layer "F.Fab")
		)
		(fp_line
			(start -0.12065 -0.2794)
			(end 0.12065 -0.2794)
			(stroke
				(width 0.1)
				(type default)
			)
			(layer "F.Fab")
		)
		(fp_line
			(start 0.120396 0.2794)
			(end -0.12065 0.2794)
			(stroke
				(width 0.1)
				(type default)
			)
			(layer "F.Fab")
		)
		(fp_line
			(start -0.12065 0.2794)
			(end -0.12065 0.3048)
			(stroke
				(width 0.1)
				(type default)
			)
			(layer "F.Fab")
		)
		(fp_line
			(start 0.67945 0.3048)
			(end 0.120396 0.3048)
			(stroke
				(width 0.1)
				(type default)
			)
			(layer "F.Fab")
		)
		(fp_line
			(start 0.120396 0.3048)
			(end 0.120396 0.2794)
			(stroke
				(width 0.1)
				(type default)
			)
			(layer "F.Fab")
		)
		(fp_line
			(start -0.12065 0.3048)
			(end -0.67945 0.3048)
			(stroke
				(width 0.1)
				(type default)
			)
			(layer "F.Fab")
		)
		(fp_line
			(start -0.67945 0.3048)
			(end -0.67945 -0.305054)
			(stroke
				(width 0.1)
				(type default)
			)
			(layer "F.Fab")
		)
		(pad "1" smd circle
			(at -0.40005 0 90)
			(size 0 0)
			(layers "F.Cu" "F.Mask" "F.Paste")
			(net "PVCCIN_CPU0_VREF")
		)
		(pad "2" smd circle
			(at 0.40005 0 90)
			(size 0 0)
			(layers "F.Cu" "F.Mask" "F.Paste")
			(net "GND")
		)
	)
)
